# BASEBOARD_FAB2 (Tioga Pass) — schematic netlist excerpt (pin names and nets, part order shuffled) for the footprints in the layout excerpt that follows; sources: Cadence DE-HDL packaged netlist, KiCad conversion of Wiwynn_Tioga_Pass_MB.brd

R1U50  RES  200.0K 1% CHIP  pkg 0402  page 169 : A = A_P3V_BAT_R ; B = P3V_BAT_SOURCE_R
C8U5  CAP_A  47UF 4V 20% X5R  pkg 0603V  page 225 : A = PVDDQ_GHJ ; B = GND
C5G44  CAP_A  22.0UF 4V 20% X6S  pkg 0603V  page 242 : A = PVDDQ_ABC ; B = GND

(kicad_pcb
	(version 20260206)
	(generator "pcbnew")
	(generator_version "10.0")
	(general
		(thickness 1.6)
		(legacy_teardrops no)
	)
	(paper "A4")
	(title_block
		(title "Wiwynn_Tioga_Pass_MB.brd")
		(comment 1 "Tioga Pass / footprints 3034-3036 of 4770")
	)
	(layers
		(0 "F.Cu" signal "TOP")
		(4 "In1.Cu" signal "L2GND")
		(6 "In2.Cu" signal "L3")
		(8 "In3.Cu" signal "L4GND")
		(10 "In4.Cu" signal "L5")
		(12 "In5.Cu" signal "L6GND")
		(14 "In6.Cu" signal "L7VCC")
		(16 "In7.Cu" signal "L8VCC")
		(18 "In8.Cu" signal "L9GND")
		(20 "In9.Cu" signal "L10")
		(22 "In10.Cu" signal "L11GND")
		(24 "In11.Cu" signal "L12")
		(26 "In12.Cu" signal "L13GND")
		(2 "B.Cu" signal "BOTTOM")
		(9 "F.Adhes" user "F.Adhesive")
		(11 "B.Adhes" user "B.Adhesive")
		(13 "F.Paste" user "Package Geometry/Pastemask Top")
		(15 "B.Paste" user "Package Geometry/Pastemask Bottom")
		(5 "F.SilkS" user "Ref Des/Silkscreen Top")
		(7 "B.SilkS" user "Ref Des/Silkscreen Bottom")
		(1 "F.Mask" user "Board Geometry/Soldermask Top")
		(3 "B.Mask" user "Board Geometry/Soldermask Bottom")
		(17 "Dwgs.User" user "User.Drawings")
		(19 "Cmts.User" user "User.Comments")
		(21 "Eco1.User" user "User.Eco1")
		(23 "Eco2.User" user "User.Eco2")
		(25 "Edge.Cuts" user "Board Geometry/Outline")
		(27 "Margin" user)
		(31 "F.CrtYd" user "Package Geometry/Place Bound Top")
		(29 "B.CrtYd" user "Package Geometry/Place Bound Bottom")
		(35 "F.Fab" user "Ref Des/Assembly Top")
		(33 "B.Fab" user "Ref Des/Assembly Bottom")
	)
	(footprint ""
		(layer "B.Cu")
		(at 253.392432 -12.954 90)
		(property "Reference" "C5G44"
			(at -1.14681 0.76708 180)
			(unlocked yes)
			(layer "B.SilkS")
			(effects
				(font
					(size 0.7874 0.5842)
					(thickness 0.1524)
				)
				(justify mirror)
			)
		)
		(property "Value" ""
			(at 0 0 90)
			(layer "B.Fab")
			(effects
				(font
					(size 1.27 1.27)
				)
				(justify mirror)
			)
		)
		(duplicate_pad_numbers_are_jumpers no)
		(fp_rect
			(start -0.4953 -0.2032)
			(end 0.4953 1.6002)
			(stroke
				(width 0)
				(type default)
			)
			(fill no)
			(layer "B.CrtYd")
		)
		(fp_line
			(start 0.4953 -0.2032)
			(end -0.4953 -0.2032)
			(stroke
				(width 0.1)
				(type default)
			)
			(layer "B.Fab")
		)
		(fp_line
			(start -0.4953 -0.2032)
			(end -0.4953 1.6002)
			(stroke
				(width 0.1)
				(type default)
			)
			(layer "B.Fab")
		)
		(fp_line
			(start 0.4953 1.6002)
			(end 0.4953 -0.2032)
			(stroke
				(width 0.1)
				(type default)
			)
			(layer "B.Fab")
		)
		(fp_line
			(start -0.4953 1.6002)
			(end 0.4953 1.6002)
			(stroke
				(width 0.1)
				(type default)
			)
			(layer "B.Fab")
		)
		(pad "1" smd rect
			(at 0 0 270)
			(size 0.762 0.889)
			(layers "B.Cu" "B.Mask" "B.Paste")
			(net "PVDDQ_ABC")
		)
		(pad "2" smd rect
			(at 0 1.397 270)
			(size 0.762 0.889)
			(layers "B.Cu" "B.Mask" "B.Paste")
			(net "GND")
		)
		(zone
			(layer "B.Cu")
			(hatch none 0.5)
			(connect_pads
				(clearance 0)
			)
			(min_thickness 0.25)
			(keepout
				(tracks not_allowed)
				(vias allowed)
				(pads allowed)
				(copperpour not_allowed)
				(footprints allowed)
			)
			(placement
				(enabled no)
				(sheetname "")
			)
			(fill
				(thermal_gap 0.5)
				(thermal_bridge_width 0.5)
				(island_removal_mode 0)
			)
			(polygon
				(pts
					(xy 253.836932 -12.573) (xy 254.344932 -12.573) (xy 254.344932 -13.335) (xy 253.836932 -13.335)
				)
			)
		)
	)
	(footprint ""
		(layer "B.Cu")
		(at 87.158068 -8.1534 -90)
		(property "Reference" "C8U5"
			(at -1.848866 0.752348 270)
			(unlocked yes)
			(layer "B.SilkS")
			(effects
				(font
					(size 1.27 0.9652)
					(thickness 0.1524)
				)
				(justify mirror)
			)
		)
		(property "Value" ""
			(at 0 0 90)
			(layer "B.Fab")
			(effects
				(font
					(size 1.27 1.27)
				)
				(justify mirror)
			)
		)
		(duplicate_pad_numbers_are_jumpers no)
		(fp_rect
			(start 0.500126 1.598422)
			(end -0.500126 -0.201422)
			(stroke
				(width 0)
				(type default)
			)
			(fill no)
			(layer "B.CrtYd")
		)
		(fp_line
			(start -0.500126 1.598422)
			(end 0.500126 1.598422)
			(stroke
				(width 0.1)
				(type default)
			)
			(layer "B.Fab")
		)
		(fp_line
			(start 0.500126 1.598422)
			(end 0.500126 -0.201422)
			(stroke
				(width 0.1)
				(type default)
			)
			(layer "B.Fab")
		)
		(fp_line
			(start -0.500126 -0.201422)
			(end -0.500126 1.598422)
			(stroke
				(width 0.1)
				(type default)
			)
			(layer "B.Fab")
		)
		(fp_line
			(start 0.500126 -0.201422)
			(end -0.500126 -0.201422)
			(stroke
				(width 0.1)
				(type default)
			)
			(layer "B.Fab")
		)
		(pad "1" smd rect
			(at 0 0 180)
			(size 0.889 0.9906)
			(layers "B.Cu" "B.Mask" "B.Paste")
			(net "PVDDQ_GHJ")
		)
		(pad "2" smd rect
			(at 0 1.397 180)
			(size 0.889 0.9906)
			(layers "B.Cu" "B.Mask" "B.Paste")
			(net "GND")
		)
		(zone
			(layer "B.Cu")
			(hatch none 0.5)
			(connect_pads
				(clearance 0)
			)
			(min_thickness 0.25)
			(keepout
				(tracks not_allowed)
				(vias allowed)
				(pads allowed)
				(copperpour not_allowed)
				(footprints allowed)
			)
			(placement
				(enabled no)
				(sheetname "")
			)
			(fill
				(thermal_gap 0.5)
				(thermal_bridge_width 0.5)
				(island_removal_mode 0)
			)
			(polygon
				(pts
					(xy 86.205568 -7.6581) (xy 86.713568 -7.6581) (xy 86.713568 -8.6487) (xy 86.205568 -8.6487)
				)
			)
		)
		(zone
			(layer "B.Cu")
			(hatch none 0.5)
			(connect_pads
				(clearance 0)
			)
			(min_thickness 0.25)
			(keepout
				(tracks allowed)
				(vias not_allowed)
				(pads allowed)
				(copperpour not_allowed)
				(footprints allowed)
			)
			(placement
				(enabled no)
				(sheetname "")
			)
			(fill
				(thermal_gap 0.5)
				(thermal_bridge_width 0.5)
				(island_removal_mode 0)
			)
			(polygon
				(pts
					(xy 86.205568 -7.6581) (xy 86.713568 -7.6581) (xy 86.713568 -8.6487) (xy 86.205568 -8.6487)
				)
			)
		)
	)
	(footprint ""
		(layer "B.Cu")
		(at 457.454 -4.2164 90)
		(property "Reference" "R1U50"
			(at 0 0 90)
			(layer "B.SilkS")
			(hide yes)
			(effects
				(font
					(size 1.27 1.27)
				)
				(justify mirror)
			)
		)
		(property "Value" ""
			(at 0 0 90)
			(layer "B.Fab")
			(effects
				(font
					(size 1.27 1.27)
				)
				(justify mirror)
			)
		)
		(duplicate_pad_numbers_are_jumpers no)
		(fp_poly
			(pts
				(xy 0.2794 -0.1016) (xy -0.2794 -0.1016) (xy -0.2794 0.9906) (xy 0.2794 0.9906)
			)
			(stroke
				(width 0)
				(type default)
			)
			(fill no)
			(layer "B.CrtYd")
		)
		(fp_line
			(start 0.2794 -0.1016)
			(end 0.2794 0.9906)
			(stroke
				(width 0.1)
				(type default)
			)
			(layer "B.Fab")
		)
		(fp_line
			(start -0.2794 -0.1016)
			(end 0.2794 -0.1016)
			(stroke
				(width 0.1)
				(type default)
			)
			(layer "B.Fab")
		)
		(fp_line
			(start 0.2794 0.9906)
			(end -0.2794 0.9906)
			(stroke
				(width 0.1)
				(type default)
			)
			(layer "B.Fab")
		)
		(fp_line
			(start -0.2794 0.9906)
			(end -0.2794 -0.1016)
			(stroke
				(width 0.1)
				(type default)
			)
			(layer "B.Fab")
		)
		(pad "1" smd rect
			(at 0 0 270)
			(size 0.508 0.508)
			(layers "B.Cu" "B.Mask" "B.Paste")
			(net "A_P3V_BAT_R")
		)
		(pad "2" smd rect
			(at 0 0.889 270)
			(size 0.508 0.508)
			(layers "B.Cu" "B.Mask" "B.Paste")
			(net "P3V_BAT_SOURCE_R")
		)
		(zone
			(layer "B.Cu")
			(hatch none 0.5)
			(connect_pads
				(clearance 0)
			)
			(min_thickness 0.25)
			(keepout
				(tracks allowed)
				(vias not_allowed)
				(pads allowed)
				(copperpour not_allowed)
				(footprints allowed)
			)
			(placement
				(enabled no)
				(sheetname "")
			)
			(fill
				(thermal_gap 0.5)
				(thermal_bridge_width 0.5)
				(island_removal_mode 0)
			)
			(polygon
				(pts
					(xy 457.708 -4.4704) (xy 457.708 -3.9624) (xy 458.089 -3.9624) (xy 458.089 -4.4704)
				)
			)
		)
		(zone
			(layer "B.Cu")
			(hatch none 0.5)
			(connect_pads
				(clearance 0)
			)
			(min_thickness 0.25)
			(keepout
				(tracks not_allowed)
				(vias allowed)
				(pads allowed)
				(copperpour not_allowed)
				(footprints allowed)
			)
			(placement
				(enabled no)
				(sheetname "")
			)
			(fill
				(thermal_gap 0.5)
				(thermal_bridge_width 0.5)
				(island_removal_mode 0)
			)
			(polygon
				(pts
					(xy 458.089 -4.4704) (xy 458.089 -3.9624) (xy 457.708 -3.9624) (xy 457.708 -4.4704)
				)
			)
		)
	)
)
